(kicad_pcb
	(version 20260206)
	(generator "pcbnew")
	(generator_version "10.0")
	(general
		(thickness 1.6)
		(legacy_teardrops no)
	)
	(paper "A4")
	(title_block
		(title "03242023_DA0F0TMBIJ0_F0T_Motherboard_J_brd_V01_OCP.brd")
		(comment 1 "Grand Teton / footprints 3569-3574 of 6105")
	)
	(layers
		(0 "F.Cu" signal "TOP")
		(4 "In1.Cu" signal "GND")
		(6 "In2.Cu" signal "IN1")
		(8 "In3.Cu" signal "GND1")
		(10 "In4.Cu" signal "IN2")
		(12 "In5.Cu" signal "GND2")
		(14 "In6.Cu" signal "IN3")
		(16 "In7.Cu" signal "GND3")
		(18 "In8.Cu" signal "VCC")
		(20 "In9.Cu" signal "VCC1")
		(22 "In10.Cu" signal "GND4")
		(24 "In11.Cu" signal "IN4")
		(26 "In12.Cu" signal "GND5")
		(28 "In13.Cu" signal "IN5")
		(30 "In14.Cu" signal "GND6")
		(32 "In15.Cu" signal "IN6")
		(34 "In16.Cu" signal "GND7")
		(2 "B.Cu" signal "BOTTOM")
		(9 "F.Adhes" user "F.Adhesive")
		(11 "B.Adhes" user "B.Adhesive")
		(13 "F.Paste" user "Package Geometry/Pastemask Top")
		(15 "B.Paste" user "Package Geometry/Pastemask Bottom")
		(5 "F.SilkS" user "Ref Des/Silkscreen Top")
		(7 "B.SilkS" user "Ref Des/Silkscreen Bottom")
		(1 "F.Mask" user "Board Geometry/Soldermask Top")
		(3 "B.Mask" user "Board Geometry/Soldermask Bottom")
		(17 "Dwgs.User" user "User.Drawings")
		(19 "Cmts.User" user "User.Comments")
		(21 "Eco1.User" user "User.Eco1")
		(23 "Eco2.User" user "User.Eco2")
		(25 "Edge.Cuts" user "Board Geometry/Outline")
		(27 "Margin" user)
		(31 "F.CrtYd" user "Package Geometry/Place Bound Top")
		(29 "B.CrtYd" user "Package Geometry/Place Bound Bottom")
		(35 "F.Fab" user "Ref Des/Assembly Top")
		(33 "B.Fab" user "Ref Des/Assembly Bottom")
	)
	(footprint ""
		(layer "F.Cu")
		(at 154.966416 -31.341568 90)
		(property "Reference" "R4453"
			(at 0 0 90)
			(layer "F.SilkS")
			(hide yes)
			(effects
				(font
					(size 1.27 1.27)
				)
			)
		)
		(property "Value" ""
			(at 0 0 90)
			(layer "F.Fab")
			(effects
				(font
					(size 1.27 1.27)
				)
			)
		)
		(duplicate_pad_numbers_are_jumpers no)
		(fp_line
			(start 0.7874 -0.4064)
			(end 0.7874 0.4064)
			(stroke
				(width 0.1524)
				(type default)
			)
			(layer "F.SilkS")
		)
		(fp_line
			(start -0.7874 -0.4064)
			(end 0.7874 -0.4064)
			(stroke
				(width 0.1524)
				(type default)
			)
			(layer "F.SilkS")
		)
		(fp_line
			(start 0.7874 0.4064)
			(end -0.7874 0.4064)
			(stroke
				(width 0.1524)
				(type default)
			)
			(layer "F.SilkS")
		)
		(fp_line
			(start -0.7874 0.4064)
			(end -0.7874 -0.4064)
			(stroke
				(width 0.1524)
				(type default)
			)
			(layer "F.SilkS")
		)
		(fp_line
			(start -0.12065 -0.305054)
			(end -0.12065 -0.2794)
			(stroke
				(width 0.1)
				(type default)
			)
			(layer "F.Fab")
		)
		(fp_line
			(start -0.67945 -0.305054)
			(end -0.12065 -0.305054)
			(stroke
				(width 0.1)
				(type default)
			)
			(layer "F.Fab")
		)
		(fp_line
			(start 0.67945 -0.3048)
			(end 0.67945 0.3048)
			(stroke
				(width 0.1)
				(type default)
			)
			(layer "F.Fab")
		)
		(fp_line
			(start 0.12065 -0.3048)
			(end 0.67945 -0.3048)
			(stroke
				(width 0.1)
				(type default)
			)
			(layer "F.Fab")
		)
		(fp_line
			(start 0.12065 -0.2794)
			(end 0.12065 -0.3048)
			(stroke
				(width 0.1)
				(type default)
			)
			(layer "F.Fab")
		)
		(fp_line
			(start -0.12065 -0.2794)
			(end 0.12065 -0.2794)
			(stroke
				(width 0.1)
				(type default)
			)
			(layer "F.Fab")
		)
		(fp_line
			(start 0.120396 0.2794)
			(end -0.12065 0.2794)
			(stroke
				(width 0.1)
				(type default)
			)
			(layer "F.Fab")
		)
		(fp_line
			(start -0.12065 0.2794)
			(end -0.12065 0.3048)
			(stroke
				(width 0.1)
				(type default)
			)
			(layer "F.Fab")
		)
		(fp_line
			(start 0.67945 0.3048)
			(end 0.120396 0.3048)
			(stroke
				(width 0.1)
				(type default)
			)
			(layer "F.Fab")
		)
		(fp_line
			(start 0.120396 0.3048)
			(end 0.120396 0.2794)
			(stroke
				(width 0.1)
				(type default)
			)
			(layer "F.Fab")
		)
		(fp_line
			(start -0.12065 0.3048)
			(end -0.67945 0.3048)
			(stroke
				(width 0.1)
				(type default)
			)
			(layer "F.Fab")
		)
		(fp_line
			(start -0.67945 0.3048)
			(end -0.67945 -0.305054)
			(stroke
				(width 0.1)
				(type default)
			)
			(layer "F.Fab")
		)
		(pad "1" smd circle
			(at -0.40005 0 90)
			(size 0 0)
			(layers "F.Cu" "F.Mask" "F.Paste")
			(net "GND")
		)
		(pad "2" smd circle
			(at 0.40005 0 90)
			(size 0 0)
			(layers "F.Cu" "F.Mask" "F.Paste")
			(net "RST_USB_HUB_2_R_N")
		)
	)
	(footprint ""
		(layer "F.Cu")
		(at 364.50143 -241.976656 -90)
		(property "Reference" "C1025"
			(at 0 0 270)
			(layer "F.SilkS")
			(hide yes)
			(effects
				(font
					(size 1.27 1.27)
				)
			)
		)
		(property "Value" ""
			(at 0 0 270)
			(layer "F.Fab")
			(effects
				(font
					(size 1.27 1.27)
				)
			)
		)
		(duplicate_pad_numbers_are_jumpers no)
		(fp_line
			(start -0.7874 0.4064)
			(end -0.7874 -0.4064)
			(stroke
				(width 0.1524)
				(type default)
			)
			(layer "F.SilkS")
		)
		(fp_line
			(start 0.7874 0.4064)
			(end -0.7874 0.4064)
			(stroke
				(width 0.1524)
				(type default)
			)
			(layer "F.SilkS")
		)
		(fp_line
			(start -0.7874 -0.4064)
			(end 0.7874 -0.4064)
			(stroke
				(width 0.1524)
				(type default)
			)
			(layer "F.SilkS")
		)
		(fp_line
			(start 0.7874 -0.4064)
			(end 0.7874 0.4064)
			(stroke
				(width 0.1524)
				(type default)
			)
			(layer "F.SilkS")
		)
		(fp_line
			(start -0.67945 0.3048)
			(end -0.67945 -0.305054)
			(stroke
				(width 0.1)
				(type default)
			)
			(layer "F.Fab")
		)
		(fp_line
			(start -0.12065 0.3048)
			(end -0.67945 0.3048)
			(stroke
				(width 0.1)
				(type default)
			)
			(layer "F.Fab")
		)
		(fp_line
			(start 0.120396 0.3048)
			(end 0.120396 0.2794)
			(stroke
				(width 0.1)
				(type default)
			)
			(layer "F.Fab")
		)
		(fp_line
			(start 0.67945 0.3048)
			(end 0.120396 0.3048)
			(stroke
				(width 0.1)
				(type default)
			)
			(layer "F.Fab")
		)
		(fp_line
			(start -0.12065 0.2794)
			(end -0.12065 0.3048)
			(stroke
				(width 0.1)
				(type default)
			)
			(layer "F.Fab")
		)
		(fp_line
			(start 0.120396 0.2794)
			(end -0.12065 0.2794)
			(stroke
				(width 0.1)
				(type default)
			)
			(layer "F.Fab")
		)
		(fp_line
			(start -0.12065 -0.2794)
			(end 0.12065 -0.2794)
			(stroke
				(width 0.1)
				(type default)
			)
			(layer "F.Fab")
		)
		(fp_line
			(start 0.12065 -0.2794)
			(end 0.12065 -0.3048)
			(stroke
				(width 0.1)
				(type default)
			)
			(layer "F.Fab")
		)
		(fp_line
			(start 0.12065 -0.3048)
			(end 0.67945 -0.3048)
			(stroke
				(width 0.1)
				(type default)
			)
			(layer "F.Fab")
		)
		(fp_line
			(start 0.67945 -0.3048)
			(end 0.67945 0.3048)
			(stroke
				(width 0.1)
				(type default)
			)
			(layer "F.Fab")
		)
		(fp_line
			(start -0.67945 -0.305054)
			(end -0.12065 -0.305054)
			(stroke
				(width 0.1)
				(type default)
			)
			(layer "F.Fab")
		)
		(fp_line
			(start -0.12065 -0.305054)
			(end -0.12065 -0.2794)
			(stroke
				(width 0.1)
				(type default)
			)
			(layer "F.Fab")
		)
		(pad "1" smd circle
			(at -0.40005 0 270)
			(size 0 0)
			(layers "F.Cu" "F.Mask" "F.Paste")
			(net "PVCCIN_CPU0")
		)
		(pad "2" smd circle
			(at 0.40005 0 270)
			(size 0 0)
			(layers "F.Cu" "F.Mask" "F.Paste")
			(net "GND")
		)
	)
	(footprint ""
		(layer "F.Cu")
		(at 27.628596 -387.246876)
		(property "Reference" "R3265"
			(at 0 0 0)
			(layer "F.SilkS")
			(hide yes)
			(effects
				(font
					(size 1.27 1.27)
				)
			)
		)
		(property "Value" ""
			(at 0 0 0)
			(layer "F.Fab")
			(effects
				(font
					(size 1.27 1.27)
				)
			)
		)
		(duplicate_pad_numbers_are_jumpers no)
		(fp_line
			(start -0.7874 -0.4064)
			(end 0.7874 -0.4064)
			(stroke
				(width 0.1524)
				(type default)
			)
			(layer "F.SilkS")
		)
		(fp_line
			(start -0.7874 0.4064)
			(end -0.7874 -0.4064)
			(stroke
				(width 0.1524)
				(type default)
			)
			(layer "F.SilkS")
		)
		(fp_line
			(start 0.7874 -0.4064)
			(end 0.7874 0.4064)
			(stroke
				(width 0.1524)
				(type default)
			)
			(layer "F.SilkS")
		)
		(fp_line
			(start 0.7874 0.4064)
			(end -0.7874 0.4064)
			(stroke
				(width 0.1524)
				(type default)
			)
			(layer "F.SilkS")
		)
		(fp_line
			(start -0.67945 -0.305054)
			(end -0.12065 -0.305054)
			(stroke
				(width 0.1)
				(type default)
			)
			(layer "F.Fab")
		)
		(fp_line
			(start -0.67945 0.3048)
			(end -0.67945 -0.305054)
			(stroke
				(width 0.1)
				(type default)
			)
			(layer "F.Fab")
		)
		(fp_line
			(start -0.12065 -0.305054)
			(end -0.12065 -0.2794)
			(stroke
				(width 0.1)
				(type default)
			)
			(layer "F.Fab")
		)
		(fp_line
			(start -0.12065 -0.2794)
			(end 0.12065 -0.2794)
			(stroke
				(width 0.1)
				(type default)
			)
			(layer "F.Fab")
		)
		(fp_line
			(start -0.12065 0.2794)
			(end -0.12065 0.3048)
			(stroke
				(width 0.1)
				(type default)
			)
			(layer "F.Fab")
		)
		(fp_line
			(start -0.12065 0.3048)
			(end -0.67945 0.3048)
			(stroke
				(width 0.1)
				(type default)
			)
			(layer "F.Fab")
		)
		(fp_line
			(start 0.120396 0.2794)
			(end -0.12065 0.2794)
			(stroke
				(width 0.1)
				(type default)
			)
			(layer "F.Fab")
		)
		(fp_line
			(start 0.120396 0.3048)
			(end 0.120396 0.2794)
			(stroke
				(width 0.1)
				(type default)
			)
			(layer "F.Fab")
		)
		(fp_line
			(start 0.12065 -0.3048)
			(end 0.67945 -0.3048)
			(stroke
				(width 0.1)
				(type default)
			)
			(layer "F.Fab")
		)
		(fp_line
			(start 0.12065 -0.2794)
			(end 0.12065 -0.3048)
			(stroke
				(width 0.1)
				(type default)
			)
			(layer "F.Fab")
		)
		(fp_line
			(start 0.67945 -0.3048)
			(end 0.67945 0.3048)
			(stroke
				(width 0.1)
				(type default)
			)
			(layer "F.Fab")
		)
		(fp_line
			(start 0.67945 0.3048)
			(end 0.120396 0.3048)
			(stroke
				(width 0.1)
				(type default)
			)
			(layer "F.Fab")
		)
		(pad "1" smd circle
			(at -0.40005 0)
			(size 0 0)
			(layers "F.Cu" "F.Mask" "F.Paste")
			(net "CLK_GEN2_GPU_FPGA_OE_OR_N")
		)
		(pad "2" smd circle
			(at 0.40005 0)
			(size 0 0)
			(layers "F.Cu" "F.Mask" "F.Paste")
			(net "GND")
		)
	)
	(footprint ""
		(layer "F.Cu")
		(at 252.735842 -92.24137)
		(property "Reference" "R1390"
			(at 0 0 0)
			(layer "F.SilkS")
			(hide yes)
			(effects
				(font
					(size 1.27 1.27)
				)
			)
		)
		(property "Value" ""
			(at 0 0 0)
			(layer "F.Fab")
			(effects
				(font
					(size 1.27 1.27)
				)
			)
		)
		(duplicate_pad_numbers_are_jumpers no)
		(fp_line
			(start -0.7874 -0.4064)
			(end 0.7874 -0.4064)
			(stroke
				(width 0.1524)
				(type default)
			)
			(layer "F.SilkS")
		)
		(fp_line
			(start -0.7874 0.4064)
			(end -0.7874 -0.4064)
			(stroke
				(width 0.1524)
				(type default)
			)
			(layer "F.SilkS")
		)
		(fp_line
			(start 0.7874 -0.4064)
			(end 0.7874 0.4064)
			(stroke
				(width 0.1524)
				(type default)
			)
			(layer "F.SilkS")
		)
		(fp_line
			(start 0.7874 0.4064)
			(end -0.7874 0.4064)
			(stroke
				(width 0.1524)
				(type default)
			)
			(layer "F.SilkS")
		)
		(fp_line
			(start -0.67945 -0.305054)
			(end -0.12065 -0.305054)
			(stroke
				(width 0.1)
				(type default)
			)
			(layer "F.Fab")
		)
		(fp_line
			(start -0.67945 0.3048)
			(end -0.67945 -0.305054)
			(stroke
				(width 0.1)
				(type default)
			)
			(layer "F.Fab")
		)
		(fp_line
			(start -0.12065 -0.305054)
			(end -0.12065 -0.2794)
			(stroke
				(width 0.1)
				(type default)
			)
			(layer "F.Fab")
		)
		(fp_line
			(start -0.12065 -0.2794)
			(end 0.12065 -0.2794)
			(stroke
				(width 0.1)
				(type default)
			)
			(layer "F.Fab")
		)
		(fp_line
			(start -0.12065 0.2794)
			(end -0.12065 0.3048)
			(stroke
				(width 0.1)
				(type default)
			)
			(layer "F.Fab")
		)
		(fp_line
			(start -0.12065 0.3048)
			(end -0.67945 0.3048)
			(stroke
				(width 0.1)
				(type default)
			)
			(layer "F.Fab")
		)
		(fp_line
			(start 0.120396 0.2794)
			(end -0.12065 0.2794)
			(stroke
				(width 0.1)
				(type default)
			)
			(layer "F.Fab")
		)
		(fp_line
			(start 0.120396 0.3048)
			(end 0.120396 0.2794)
			(stroke
				(width 0.1)
				(type default)
			)
			(layer "F.Fab")
		)
		(fp_line
			(start 0.12065 -0.3048)
			(end 0.67945 -0.3048)
			(stroke
				(width 0.1)
				(type default)
			)
			(layer "F.Fab")
		)
		(fp_line
			(start 0.12065 -0.2794)
			(end 0.12065 -0.3048)
			(stroke
				(width 0.1)
				(type default)
			)
			(layer "F.Fab")
		)
		(fp_line
			(start 0.67945 -0.3048)
			(end 0.67945 0.3048)
			(stroke
				(width 0.1)
				(type default)
			)
			(layer "F.Fab")
		)
		(fp_line
			(start 0.67945 0.3048)
			(end 0.120396 0.3048)
			(stroke
				(width 0.1)
				(type default)
			)
			(layer "F.Fab")
		)
		(pad "1" smd circle
			(at -0.40005 0)
			(size 0 0)
			(layers "F.Cu" "F.Mask" "F.Paste")
			(net "FM_PLD_CLKS_DEV_EN")
		)
		(pad "2" smd circle
			(at 0.40005 0)
			(size 0 0)
			(layers "F.Cu" "F.Mask" "F.Paste")
			(net "GND")
		)
	)
	(footprint ""
		(layer "F.Cu")
		(at 163.50488 -437.479948)
		(property "Reference" "R3448"
			(at 0 0 0)
			(layer "F.SilkS")
			(hide yes)
			(effects
				(font
					(size 1.27 1.27)
				)
			)
		)
		(property "Value" ""
			(at 0 0 0)
			(layer "F.Fab")
			(effects
				(font
					(size 1.27 1.27)
				)
			)
		)
		(duplicate_pad_numbers_are_jumpers no)
		(fp_line
			(start -0.7874 -0.4064)
			(end 0.7874 -0.4064)
			(stroke
				(width 0.1524)
				(type default)
			)
			(layer "F.SilkS")
		)
		(fp_line
			(start -0.7874 0.4064)
			(end -0.7874 -0.4064)
			(stroke
				(width 0.1524)
				(type default)
			)
			(layer "F.SilkS")
		)
		(fp_line
			(start 0.7874 -0.4064)
			(end 0.7874 0.4064)
			(stroke
				(width 0.1524)
				(type default)
			)
			(layer "F.SilkS")
		)
		(fp_line
			(start 0.7874 0.4064)
			(end -0.7874 0.4064)
			(stroke
				(width 0.1524)
				(type default)
			)
			(layer "F.SilkS")
		)
		(fp_line
			(start -0.67945 -0.305054)
			(end -0.12065 -0.305054)
			(stroke
				(width 0.1)
				(type default)
			)
			(layer "F.Fab")
		)
		(fp_line
			(start -0.67945 0.3048)
			(end -0.67945 -0.305054)
			(stroke
				(width 0.1)
				(type default)
			)
			(layer "F.Fab")
		)
		(fp_line
			(start -0.12065 -0.305054)
			(end -0.12065 -0.2794)
			(stroke
				(width 0.1)
				(type default)
			)
			(layer "F.Fab")
		)
		(fp_line
			(start -0.12065 -0.2794)
			(end 0.12065 -0.2794)
			(stroke
				(width 0.1)
				(type default)
			)
			(layer "F.Fab")
		)
		(fp_line
			(start -0.12065 0.2794)
			(end -0.12065 0.3048)
			(stroke
				(width 0.1)
				(type default)
			)
			(layer "F.Fab")
		)
		(fp_line
			(start -0.12065 0.3048)
			(end -0.67945 0.3048)
			(stroke
				(width 0.1)
				(type default)
			)
			(layer "F.Fab")
		)
		(fp_line
			(start 0.120396 0.2794)
			(end -0.12065 0.2794)
			(stroke
				(width 0.1)
				(type default)
			)
			(layer "F.Fab")
		)
		(fp_line
			(start 0.120396 0.3048)
			(end 0.120396 0.2794)
			(stroke
				(width 0.1)
				(type default)
			)
			(layer "F.Fab")
		)
		(fp_line
			(start 0.12065 -0.3048)
			(end 0.67945 -0.3048)
			(stroke
				(width 0.1)
				(type default)
			)
			(layer "F.Fab")
		)
		(fp_line
			(start 0.12065 -0.2794)
			(end 0.12065 -0.3048)
			(stroke
				(width 0.1)
				(type default)
			)
			(layer "F.Fab")
		)
		(fp_line
			(start 0.67945 -0.3048)
			(end 0.67945 0.3048)
			(stroke
				(width 0.1)
				(type default)
			)
			(layer "F.Fab")
		)
		(fp_line
			(start 0.67945 0.3048)
			(end 0.120396 0.3048)
			(stroke
				(width 0.1)
				(type default)
			)
			(layer "F.Fab")
		)
		(pad "1" smd circle
			(at -0.40005 0)
			(size 0 0)
			(layers "F.Cu" "F.Mask" "F.Paste")
			(net "P3V3_AUX")
		)
		(pad "2" smd circle
			(at 0.40005 0)
			(size 0 0)
			(layers "F.Cu" "F.Mask" "F.Paste")
			(net "GPU_FPGA_BOOT_EN")
		)
	)
	(footprint ""
		(layer "F.Cu")
		(at 98.33864 -33.736788 180)
		(property "Reference" "R3264"
			(at 0 0 180)
			(layer "F.SilkS")
			(hide yes)
			(effects
				(font
					(size 1.27 1.27)
				)
			)
		)
		(property "Value" ""
			(at 0 0 180)
			(layer "F.Fab")
			(effects
				(font
					(size 1.27 1.27)
				)
			)
		)
		(duplicate_pad_numbers_are_jumpers no)
		(fp_line
			(start 0.7874 0.4064)
			(end -0.7874 0.4064)
			(stroke
				(width 0.1524)
				(type default)
			)
			(layer "F.SilkS")
		)
		(fp_line
			(start 0.7874 -0.4064)
			(end 0.7874 0.4064)
			(stroke
				(width 0.1524)
				(type default)
			)
			(layer "F.SilkS")
		)
		(fp_line
			(start -0.7874 0.4064)
			(end -0.7874 -0.4064)
			(stroke
				(width 0.1524)
				(type default)
			)
			(layer "F.SilkS")
		)
		(fp_line
			(start -0.7874 -0.4064)
			(end 0.7874 -0.4064)
			(stroke
				(width 0.1524)
				(type default)
			)
			(layer "F.SilkS")
		)
		(fp_line
			(start 0.67945 0.3048)
			(end 0.120396 0.3048)
			(stroke
				(width 0.1)
				(type default)
			)
			(layer "F.Fab")
		)
		(fp_line
			(start 0.67945 -0.3048)
			(end 0.67945 0.3048)
			(stroke
				(width 0.1)
				(type default)
			)
			(layer "F.Fab")
		)
		(fp_line
			(start 0.12065 -0.2794)
			(end 0.12065 -0.3048)
			(stroke
				(width 0.1)
				(type default)
			)
			(layer "F.Fab")
		)
		(fp_line
			(start 0.12065 -0.3048)
			(end 0.67945 -0.3048)
			(stroke
				(width 0.1)
				(type default)
			)
			(layer "F.Fab")
		)
		(fp_line
			(start 0.120396 0.3048)
			(end 0.120396 0.2794)
			(stroke
				(width 0.1)
				(type default)
			)
			(layer "F.Fab")
		)
		(fp_line
			(start 0.120396 0.2794)
			(end -0.12065 0.2794)
			(stroke
				(width 0.1)
				(type default)
			)
			(layer "F.Fab")
		)
		(fp_line
			(start -0.12065 0.3048)
			(end -0.67945 0.3048)
			(stroke
				(width 0.1)
				(type default)
			)
			(layer "F.Fab")
		)
		(fp_line
			(start -0.12065 0.2794)
			(end -0.12065 0.3048)
			(stroke
				(width 0.1)
				(type default)
			)
			(layer "F.Fab")
		)
		(fp_line
			(start -0.12065 -0.2794)
			(end 0.12065 -0.2794)
			(stroke
				(width 0.1)
				(type default)
			)
			(layer "F.Fab")
		)
		(fp_line
			(start -0.12065 -0.305054)
			(end -0.12065 -0.2794)
			(stroke
				(width 0.1)
				(type default)
			)
			(layer "F.Fab")
		)
		(fp_line
			(start -0.67945 0.3048)
			(end -0.67945 -0.305054)
			(stroke
				(width 0.1)
				(type default)
			)
			(layer "F.Fab")
		)
		(fp_line
			(start -0.67945 -0.305054)
			(end -0.12065 -0.305054)
			(stroke
				(width 0.1)
				(type default)
			)
			(layer "F.Fab")
		)
		(pad "1" smd circle
			(at -0.40005 0 180)
			(size 0 0)
			(layers "F.Cu" "F.Mask" "F.Paste")
			(net "HP_LVC3_OCP_V3_2_R_EN")
		)
		(pad "2" smd circle
			(at 0.40005 0 180)
			(size 0 0)
			(layers "F.Cu" "F.Mask" "F.Paste")
			(net "HP_LVC3_OCP_V3_2_EN")
		)
	)
)
